# TIMECARD (Time Appliance Project (Time Card)) — schematic netlist excerpt (pin names and nets, part order shuffled) for the footprints in the layout excerpt that follows; sources: Cadence DE-HDL packaged netlist, KiCad conversion of R4006-B0001-02_R01.brd

C168  CAPACITOR  22UF 10V 20%  pkg SMC_0805R_H057  page 14 : \1\ = XP2R5V_FPGA ; \2\ = SG
R196  RESISTOR  100OHM 1%  pkg SMC_0402R_H016  page 10 : \1\ = FPGA_MGTAVTT ; \2\ = FPGA_MGTRREF

(kicad_pcb
	(version 20260206)
	(generator "pcbnew")
	(generator_version "10.0")
	(general
		(thickness 1.6)
		(legacy_teardrops no)
	)
	(paper "A4")
	(title_block
		(title "timecard-production-celestica-r4006 — R4006-B0001-02_R01.brd")
		(comment 1 "Time Appliance Project (Time Card) / footprints 892-893 of 1113")
	)
	(layers
		(0 "F.Cu" signal "TOP")
		(4 "In1.Cu" signal "L02_GND1")
		(6 "In2.Cu" signal "L03_SIG1")
		(8 "In3.Cu" signal "L04_GND2")
		(10 "In4.Cu" signal "L05_VCC1")
		(12 "In5.Cu" signal "L06_VCC2")
		(14 "In6.Cu" signal "L07_GND3")
		(16 "In7.Cu" signal "L08_SIG2")
		(18 "In8.Cu" signal "L09_GND4")
		(2 "B.Cu" signal "BOTTOM")
		(9 "F.Adhes" user "F.Adhesive")
		(11 "B.Adhes" user "B.Adhesive")
		(13 "F.Paste" user "Package Geometry/Pastemask Top")
		(15 "B.Paste" user "Package Geometry/Pastemask Bottom")
		(5 "F.SilkS" user "Ref Des/Silkscreen Top")
		(7 "B.SilkS" user "Ref Des/Silkscreen Bottom")
		(1 "F.Mask" user "Board Geometry/Soldermask Top")
		(3 "B.Mask" user "Board Geometry/Soldermask Bottom")
		(17 "Dwgs.User" user "User.Drawings")
		(19 "Cmts.User" user "User.Comments")
		(21 "Eco1.User" user "User.Eco1")
		(23 "Eco2.User" user "User.Eco2")
		(25 "Edge.Cuts" user "Board Geometry/Outline")
		(27 "Margin" user)
		(31 "F.CrtYd" user "Package Geometry/Place Bound Top")
		(29 "B.CrtYd" user "Package Geometry/Place Bound Bottom")
		(35 "F.Fab" user "Ref Des/Assembly Top")
		(33 "B.Fab" user "Ref Des/Assembly Bottom")
	)
	(footprint ""
		(layer "B.Cu")
		(at 126.1364 -32.0802)
		(property "Reference" "C168"
			(at -0.127 2.07137 0)
			(unlocked yes)
			(layer "B.SilkS")
			(effects
				(font
					(size 0.7874 0.5842)
					(thickness 0.1524)
				)
				(justify mirror)
			)
		)
		(property "Value" "VAL*"
			(at -0.0762 3.134106 0)
			(unlocked yes)
			(layer "B.Fab")
			(hide yes)
			(effects
				(font
					(size 0.7874 0.5842)
					(thickness 0.1524)
				)
				(justify mirror)
			)
		)
		(property "Tolerance" "TOL*"
			(at -0.0762 4.048506 0)
			(unlocked yes)
			(layer "Cmts.User")
			(hide yes)
			(effects
				(font
					(size 0.7874 0.5842)
					(thickness 0.1524)
				)
				(justify mirror)
			)
		)
		(property "User Part Number" "PARTNUM*"
			(at -0.1016 5.013706 0)
			(unlocked yes)
			(layer "Cmts.User")
			(hide yes)
			(effects
				(font
					(size 0.7874 0.5842)
					(thickness 0.1524)
				)
				(justify mirror)
			)
		)
		(property "Device Type" "CAPACITOR-G107-0F226-CM,22UF,2A"
			(at -0.0508 2.194306 0)
			(unlocked yes)
			(layer "B.Fab")
			(hide yes)
			(effects
				(font
					(size 0.7874 0.5842)
					(thickness 0.1524)
				)
				(justify mirror)
			)
		)
		(duplicate_pad_numbers_are_jumpers no)
		(fp_line
			(start -1.5748 -0.9398)
			(end 1.5748 -0.9398)
			(stroke
				(width 0.1)
				(type default)
			)
			(layer "B.SilkS")
		)
		(fp_line
			(start -1.5748 0.9398)
			(end -1.5748 -0.9398)
			(stroke
				(width 0.1)
				(type default)
			)
			(layer "B.SilkS")
		)
		(fp_line
			(start 1.5748 -0.9398)
			(end 1.5748 0.9398)
			(stroke
				(width 0.1)
				(type default)
			)
			(layer "B.SilkS")
		)
		(fp_line
			(start 1.5748 0.9398)
			(end -1.5748 0.9398)
			(stroke
				(width 0.1)
				(type default)
			)
			(layer "B.SilkS")
		)
		(fp_rect
			(start -1.5748 -0.9398)
			(end 1.5748 0.9398)
			(stroke
				(width 0)
				(type default)
			)
			(fill no)
			(layer "B.CrtYd")
		)
		(fp_line
			(start -1.016 -0.635)
			(end 1.016 -0.635)
			(stroke
				(width 0.1)
				(type default)
			)
			(layer "B.Fab")
		)
		(fp_line
			(start -1.016 0.635)
			(end -1.016 -0.635)
			(stroke
				(width 0.1)
				(type default)
			)
			(layer "B.Fab")
		)
		(fp_line
			(start 1.016 -0.635)
			(end 1.016 0.635)
			(stroke
				(width 0.1)
				(type default)
			)
			(layer "B.Fab")
		)
		(fp_line
			(start 1.016 0.635)
			(end -1.016 0.635)
			(stroke
				(width 0.1)
				(type default)
			)
			(layer "B.Fab")
		)
		(pad "1" smd rect
			(at 0.8382 0 180)
			(size 0.9652 1.3716)
			(layers "B.Cu" "B.Mask" "B.Paste")
			(net "XP2R5V_FPGA")
		)
		(pad "2" smd rect
			(at -0.8382 0 180)
			(size 0.9652 1.3716)
			(layers "B.Cu" "B.Mask" "B.Paste")
			(net "SG")
		)
		(zone
			(layer "B.Cu")
			(hatch none 0.5)
			(connect_pads
				(clearance 0)
			)
			(min_thickness 0.25)
			(keepout
				(tracks allowed)
				(vias not_allowed)
				(pads allowed)
				(copperpour not_allowed)
				(footprints allowed)
			)
			(placement
				(enabled no)
				(sheetname "")
			)
			(fill
				(thermal_gap 0.5)
				(thermal_bridge_width 0.5)
				(island_removal_mode 0)
			)
			(polygon
				(pts
					(xy 125.9078 -32.7152) (xy 125.9078 -31.4452) (xy 126.365 -31.4452) (xy 126.365 -32.7152)
				)
			)
		)
	)
	(footprint ""
		(layer "B.Cu")
		(at 94.615 -43.688 180)
		(property "Reference" "R196"
			(at 3.556 0.08763 0)
			(unlocked yes)
			(layer "B.SilkS")
			(effects
				(font
					(size 0.7874 0.5842)
					(thickness 0.1524)
				)
				(justify mirror)
			)
		)
		(property "Value" "VAL*"
			(at -0.02032 2.13233 180)
			(unlocked yes)
			(layer "B.Fab")
			(hide yes)
			(effects
				(font
					(size 0.7874 0.5842)
					(thickness 0.1524)
				)
				(justify mirror)
			)
		)
		(property "Tolerance" "TOL*"
			(at -0.044704 3.05435 180)
			(unlocked yes)
			(layer "Cmts.User")
			(hide yes)
			(effects
				(font
					(size 0.7874 0.5842)
					(thickness 0.1524)
				)
				(justify mirror)
			)
		)
		(property "User Part Number" "PARTNUM*"
			(at -0.02032 4.024884 180)
			(unlocked yes)
			(layer "Cmts.User")
			(hide yes)
			(effects
				(font
					(size 0.7874 0.5842)
					(thickness 0.1524)
				)
				(justify mirror)
			)
		)
		(property "Device Type" "RESISTOR-G155-11000-01,100OHM,A"
			(at -0.008382 1.210564 180)
			(unlocked yes)
			(layer "B.Fab")
			(hide yes)
			(effects
				(font
					(size 0.7874 0.5842)
					(thickness 0.1524)
				)
				(justify mirror)
			)
		)
		(duplicate_pad_numbers_are_jumpers no)
		(fp_line
			(start 1.143 0.5588)
			(end -1.143 0.5588)
			(stroke
				(width 0.1)
				(type default)
			)
			(layer "B.SilkS")
		)
		(fp_line
			(start 1.143 -0.5588)
			(end 1.143 0.5588)
			(stroke
				(width 0.1)
				(type default)
			)
			(layer "B.SilkS")
		)
		(fp_line
			(start -1.143 0.5588)
			(end -1.143 -0.5588)
			(stroke
				(width 0.1)
				(type default)
			)
			(layer "B.SilkS")
		)
		(fp_line
			(start -1.143 -0.5588)
			(end 1.143 -0.5588)
			(stroke
				(width 0.1)
				(type default)
			)
			(layer "B.SilkS")
		)
		(fp_rect
			(start 1.143 -0.5588)
			(end -1.143 0.5588)
			(stroke
				(width 0)
				(type default)
			)
			(fill no)
			(layer "B.CrtYd")
		)
		(fp_line
			(start 0.508 0.3048)
			(end -0.508 0.3048)
			(stroke
				(width 0.1)
				(type default)
			)
			(layer "B.Fab")
		)
		(fp_line
			(start 0.508 -0.3048)
			(end 0.508 0.3048)
			(stroke
				(width 0.1)
				(type default)
			)
			(layer "B.Fab")
		)
		(fp_line
			(start -0.508 0.3048)
			(end -0.508 -0.3048)
			(stroke
				(width 0.1)
				(type default)
			)
			(layer "B.Fab")
		)
		(fp_line
			(start -0.508 -0.3048)
			(end 0.508 -0.3048)
			(stroke
				(width 0.1)
				(type default)
			)
			(layer "B.Fab")
		)
		(pad "1" smd rect
			(at 0.5334 0)
			(size 0.7112 0.6096)
			(layers "B.Cu" "B.Mask" "B.Paste")
			(net "FPGA_MGTAVTT")
		)
		(pad "2" smd rect
			(at -0.5334 0)
			(size 0.7112 0.6096)
			(layers "B.Cu" "B.Mask" "B.Paste")
			(net "FPGA_MGTRREF")
		)
		(zone
			(layer "B.Cu")
			(hatch none 0.5)
			(connect_pads
				(clearance 0)
			)
			(min_thickness 0.25)
			(keepout
				(tracks allowed)
				(vias not_allowed)
				(pads allowed)
				(copperpour not_allowed)
				(footprints allowed)
			)
			(placement
				(enabled no)
				(sheetname "")
			)
			(fill
				(thermal_gap 0.5)
				(thermal_bridge_width 0.5)
				(island_removal_mode 0)
			)
			(polygon
				(pts
					(xy 94.5388 -43.3832) (xy 94.6912 -43.3832) (xy 94.6912 -43.9928) (xy 94.5388 -43.9928)
				)
			)
		)
	)
)
